# BASEBOARD_FAB2 (Tioga Pass) — schematic parts with pin connectivity, parts 4676–4676 of 4751; source: Cadence DE-HDL packaged netlist (pstxprt.dat, pstxnet.dat, pstchip.dat)

U7C1  LBG_CORE_QAT_EXT_D  IC  pkg BGA1  page 114  (pins 1-312 of 1310)
  A5  VSS(484)  GROUND  = GND
  A7  VSS(483)  GROUND  = GND
  A9  VSS(482)  GROUND  = GND
  A11  RSVD(21)  UNSPEC  = TP_PCH_RSVD21
  A13  GPD11_GBEPHY  BI  = FM_GBE_LOM_DISABLE_N
  A15  GPD9  BI  = FM_BMC_CPLD_MP_RST_N
  A18  VSS(448)  GROUND  = GND
  A20  CLKOUT_SRCP(14)  BI  = CLK_100M_SPRV_DP
  A22  VSS(447)  GROUND  = GND
  A24  CLKOUT_SRCP(13)  BI  = NC
  A26  RSVD(65)  UNSPEC  = TP_PCH_RSVD65
  A28  CLKOUT_SRCN(4)  BI  = CLK_100M_PCH_SLOTX24_S2_DN
  A30  VSS(446)  GROUND  = GND
  A32  CLKOUT_NSSCCAP0N  BI  = TP_CLK_100M_NSSCC0_DN
  A34  VSS(445)  GROUND  = GND
  A37  VSS(444)  GROUND  = GND
  A39  CLKOUT_ITPXDPN  BI  = CLK_100M_PCH_XDP_DN
  A41  VSS(443)  GROUND  = GND
  A43  DMI_RXP(1)  BI  = DMI_CPU0_PCH_TX_C_DP<1>
  A45  DMI_RXP(3)  BI  = DMI_CPU0_PCH_TX_C_DP<3>
  A48  PCIEUP_0_RXP  BI  = P3E_CPU0_PE1_PCH_TXP<0>
  A50  PCIEUP_2_RXP  BI  = P3E_CPU0_PE1_PCH_TXP<2>
  A52  PCIEUP_4_RXP  BI  = P3E_CPU0_PE1_PCH_TXP<4>
  A54  PCIEUP_6_RXP  BI  = P3E_CPU0_PE1_PCH_TXP<6>
  A57  PCIEUP_8_RXP  BI  = P3E_CPU0_PE1_PCH_C_TXN<8>
  A59  PCIEUP_10_RXP  BI  = P3E_CPU0_PE1_PCH_C_TXN<10>
  A61  PCIEUP_12_RXP  BI  = P3E_CPU0_PE1_PCH_C_TXN<12>
  A63  PCIEUP_14_RXP  BI  = P3E_CPU0_PE1_PCH_C_TXN<14>
  A65  VSS(481)  GROUND  = GND
  A66  VSS(480)  GROUND  = GND
  A68  VSS(479)  GROUND  = GND
  A70  VSS(468)  GROUND  = GND
  AA2  GPP_A7_PIRQA_N_ESPI_ALERT0_N  BI  = IRQ_PIRQA_SPI_TPM_N
  AA4  GPP_A10_CLKOUT_LPC1  BI  = NC
  AA9  GPP_L17_TESTCH1_D6  BI  = FM_CPU1_PROCHOT_PCH_N
  AA13  GPP_L14_TESTCH1_D3  BI  = H_CPU1_MEMGHJ_MEMHOT_PCH_N
  AA17  GPP_L7_TESTCH0_D5  BI  = FM_PRSNT_2_6_N
  AA20  GPP_L6_TESTCH0_D4  BI  = FM_PRSNT_2_5_N
  AA24  VCCPRIM_1P05(18)  POWER  = P1V05_PCH_STBY
  AA26  VSS(297)  GROUND  = GND
  AA27  VSS(296)  GROUND  = GND
  AA29  VCCPRIM_AVID(47)  POWER  = PVNN_PCH_STBY
  AA30  VCCPRIM_AVID(46)  POWER  = PVNN_PCH_STBY
  AA32  VCCPRIM_AVID(45)  POWER  = PVNN_PCH_STBY
  AA34  VCCPRIM_AVID(44)  POWER  = PVNN_PCH_STBY
  AA36  VCCPRIM_AVID(43)  POWER  = PVNN_PCH_STBY
  AA37  VCCPRIM_AVID(42)  POWER  = PVNN_PCH_STBY
  AA39  VCCPRIM_AVID(41)  POWER  = PVNN_PCH_STBY
  AA41  VCCPRIM_AVID(40)  POWER  = PVNN_PCH_STBY
  AA43  VSS(295)  GROUND  = GND
  AA45  VCCPRIM_1P05(9)  POWER  = P1V05_PCH_STBY
  AA46  VCCPRIM_1P05(8)  POWER  = P1V05_PCH_STBY
  AA48  VSS(294)  GROUND  = GND
  AA50  VSS(309)  GROUND  = GND
  AA54  RSVD(32)  UNSPEC  = TP_PCH_RSVD32
  AA58  RSVD(2)  UNSPEC  = TP_PCH_RSVD2
  AA61  PCIE19_UP7_SATA7_RXN  BI  = SATA6G_PCH_PCIE_UP_SATA_RXN<7>
  AA65  PCIEUP_15_TXP  BI  = P3E_CPU0_PE1_PCH_R_RXP<15>
  AA69  RSVD(51)  UNSPEC  = TP_PCH_RSVD51
  AA71  RSVD(52)  UNSPEC  = TP_PCH_RSVD52
  AB1  GPP_A8_CLKRUN_N  BI  = PU_LPC_CLKRUN_N
  AB3  GPP_A14_ESPI_RESET_N  BI  = FM_MB_SLOT_ID1
  AB5  VSS(293)  GROUND  = GND
  AB68  VSS(292)  GROUND  = GND
  AB70  VSS(291)  GROUND  = GND
  AB72  VSS(290)  GROUND  = GND
  AC2  GPP_A11_PME_N  BI  = PU_LPC_PME_N
  AC4  GPP_A15_SUSACK_N  BI  = FM_MB_SLOT_ID2
  AC7  VSS(275)  GROUND  = GND
  AC11  VSS(289)  GROUND  = GND
  AC15  VSS(288)  GROUND  = GND
  AC18  VSS(287)  GROUND  = GND
  AC22  VSS(286)  GROUND  = GND
  AC26  VCCPRIM_1P05(7)  POWER  = P1V05_PCH_STBY
  AC27  VSS(283)  GROUND  = GND
  AC29  VCCPRIM_AVID(39)  POWER  = PVNN_PCH_STBY
  AC30  VCCPRIM_AVID(38)  POWER  = PVNN_PCH_STBY
  AC32  VCCPRIM_AVID(37)  POWER  = PVNN_PCH_STBY
  AC34  VCCPRIM_AVID(36)  POWER  = PVNN_PCH_STBY
  AC36  VCCPRIM_AVID(35)  POWER  = PVNN_PCH_STBY
  AC37  VCCPRIM_AVID(34)  POWER  = PVNN_PCH_STBY
  AC39  VCCPRIM_AVID(33)  POWER  = PVNN_PCH_STBY
  AC41  VCCPRIM_AVID(32)  POWER  = PVNN_PCH_STBY
  AC43  VSS(282)  GROUND  = GND
  AC45  VSS(285)  GROUND  = GND
  AC46  VSS(281)  GROUND  = GND
  AC48  VSS(280)  GROUND  = GND
  AC52  VSS(279)  GROUND  = GND
  AC56  RSVD(1)  UNSPEC  = TP_PCH_RSVD1
  AC59  VSS(278)  GROUND  = GND
  AC63  VSS(277)  GROUND  = GND
  AC66  VSS(276)  GROUND  = GND
  AC69  PCIE11_SSATA5_GBE_TXN  BI  = NC
  AC71  PCIE11_SSATA5_GBE_TXP  BI  = NC
  AD1  GPP_A17  BI  = FM_CPU_BMC_INIT
  AD3  GPP_A18  BI  = RST_PCH_SYSRST_BTN_OUT_N
  AD5  VSS(274)  GROUND  = GND
  AD9  GPP_L8_TESTCH0_D6  BI  = FM_OCP_MEZZB_PRES_1V05_PCH_N
  AD13  GPP_L13_TESTCH1_D2  BI  = H_CPU0_MEMDEF_MEMHOT_PCH_N
  AD17  GPP_L9_TESTCH0_D7  BI  = FM_OCP_MEZZC_PRES_1V05_PCH_N
  AD20  GPP_L11_TESTCH1_D0  BI  = TP_PCH_GPP_L11
  AD24  VCCP_3P3(2)  POWER  = P3V3_STBY
  AD50  VCCA_CLKXTAL_1P05  POWER  = P1V05_PCH_STBY_VCCA_XTAL
  AD54  PRDY_N  BI  = XDP_PRDY_N
  AD58  VSS(284)  GROUND  = GND
  AD61  PCIE19_UP7_SATA7_RXP  BI  = SATA6G_PCH_PCIE_UP_SATA_RXP<7>
  AD65  VSS(273)  GROUND  = GND
  AD68  VSS(272)  GROUND  = GND
  AD70  PCIE10_SSATA4_TXN  BI  = NC
  AD72  PCIE10_SSATA4_TXP  BI  = NC
  AE2  GPP_A21  BI  = FM_OCP_MEZZA_PRES_R
  AE4  GPP_A22  BI  = FM_TPM_PRES_N
  AE7  GPP_L18_TESTCH1_D7  BI  = FM_CPU_ERR0_PCH_N
  AE11  GPP_L4_TESTCH0_D2  BI  = FM_PRSNT_2_3_N
  AE15  GPP_L3_TESTCH0_D1  BI  = FM_PRSNT_2_2_N
  AE18  GPP_L2_TESTCH0_D0  BI  = FM_PRSNT_2_1_N
  AE22  VSS(172)  GROUND  = GND
  AE26  VCCP_1P8(1)  POWER  = P1V8_PCH_STBY
  AE27  VCCMPHY_1P05(13)  POWER  = P1V05_PCH_STBY
  AE29  VSS(271)  GROUND  = GND
  AE30  VCCPRIM_AVID(30)  POWER  = PVNN_PCH_STBY
  AE32  VCCPRIM_AVID(29)  POWER  = PVNN_PCH_STBY
  AE34  VCCPRIM_AVID(28)  POWER  = PVNN_PCH_STBY
  AE36  VCCPRIM_AVID(27)  POWER  = PVNN_PCH_STBY
  AE37  VCCPRIM_AVID(26)  POWER  = PVNN_PCH_STBY
  AE39  VCCPRIM_AVID(25)  POWER  = PVNN_PCH_STBY
  AE41  VCCPRIM_AVID(24)  POWER  = PVNN_PCH_STBY
  AE43  VSS(347)  GROUND  = GND
  AE45  VCCA_PLL1_1P05  POWER  = P1V05_PCH_STBY_VCCA_PLL1
  AE46  VCCA_CLKFILT_1P05(4)  POWER  = P1V05_PCH_STBY_ISCLK_PLL
  AE48  VSS(269)  GROUND  = GND
  AE52  VSS(268)  GROUND  = GND
  AE56  VSS(267)  GROUND  = GND
  AE59  VSS(266)  GROUND  = GND
  AE63  VSS(265)  GROUND  = GND
  AE66  VSS(264)  GROUND  = GND
  AE69  PCIE9_SSATA3_TXN  BI  = NC
  AE71  PCIE9_SSATA3_TXP  BI  = NC
  AF1  VSS(263)  GROUND  = GND
  AF3  VSS(257)  GROUND  = GND
  AF5  VSS(261)  GROUND  = GND
  AF9  VSS(260)  GROUND  = GND
  AF13  VSS(262)  GROUND  = GND
  AF17  VSS(259)  GROUND  = GND
  AF20  GPP_L10_TESTCH0_CLK  BI  = TP_PCH_GPP_L10
  AF24  VSS(258)  GROUND  = GND
  AF50  VSS(323)  GROUND  = GND
  AF54  JTAGX  BI  = XDP_PCH_CPU_TCK0
  AF58  PCIEUP_RCOMPN  BI  = A_PCIEUP_RCOMP_N
  AF61  RSVD(0)  UNSPEC  = TP_PCH_RSVD0
  AF65  PCIE16_UP4_SATA4_RXN  BI  = SATA6G_PCH_PCIE_UP_SATA_RXN<4>
  AF68  VSS(256)  GROUND  = GND
  AF70  PCIE8_SSATA2_GBE_TXN  BI  = NC
  AF72  PCIE8_SSATA2_GBE_TXP  BI  = NC
  AG7  GPP_F0_SATAXPCIE3_SATAGP3  BI  = IRQ_OC_DETECT_N
  AG11  GPP_L19_TESTCH1_CLK  BI  = FM_CPU_ERR1_PCH_N
  AG15  RSVD(5)  UNSPEC  = TP_PCH_RSVD5
  AG18  INTRUDER_N  BI  = FM_INTRUDER_HDR_PCH_N
  AG22  VCCRTCEXT  POWER  = A_PVCCRTC_EXT_CAP
  AG26  VSS(255)  GROUND  = GND
  AG27  VCCPHDA_1P8  POWER  = P1V8_PCH_STBY
  AG29  VCCPRTCPRIM_3P3  POWER  = P3V3_STBY
  AG30  VSS(254)  GROUND  = GND
  AG32  VCCPRIM_AVID(23)  POWER  = PVNN_PCH_STBY
  AG34  VCCPRIM_AVID(22)  POWER  = PVNN_PCH_STBY
  AG36  VCCPRIM_AVID(21)  POWER  = PVNN_PCH_STBY
  AG37  VCCPRIM_AVID(20)  POWER  = PVNN_PCH_STBY
  AG39  VCCPRIM_AVID(19)  POWER  = PVNN_PCH_STBY
  AG41  VSS(253)  GROUND  = GND
  AG43  VSS(252)  GROUND  = GND
  AG45  VCCA_CLKFILT_1P05(1)  POWER  = P1V05_PCH_STBY_ISCLK_PLL
  AG46  VSS(322)  GROUND  = GND
  AG48  VCCA_PLL0_1P05  POWER  = P1V05_PCH_STBY_VCCA_PLL0
  AG52  VSS(251)  GROUND  = GND
  AG56  VSS(250)  GROUND  = GND
  AG59  VSS(249)  GROUND  = GND
  AG63  PCIE17_UP5_SATA5_RXP  BI  = SATA6G_PCH_PCIE_UP_SATA_RXP<5>
  AG66  VSS(248)  GROUND  = GND
  AH2  GPP_K7  BI  = RMII_BMC_PCH_SPRNGVLLE_RXER_R
  AH4  GPP_K10_PE_RST_N  BI  = RST_PCIE_PCH_PERST_N
  AH9  GPP_F8_SATA_DEVSLP6  BI  = JTAG_PCH_PLD_TMS
  AH13  GPP_F4_SATAXPCIE7_SATAGP7  BI  = FM_BMC_READY_R1_N
  AH17  GPP_F5_SATA_DEVSLP3  BI  = FM_BIOS_USB_RECOVERY
  AH20  VSS(247)  GROUND  = GND
  AH24  VCCPDSW_3P3  POWER  = P3V3_STBY
  AH50  VCCA_CLKUNF_1P05(0)  POWER  = P1V05_PCH_STBY
  AH54  JTAG_TMS  BI  = XDP_TMS
  AH58  PCIEUP_RCOMPP  BI  = A_PCIEUP_RCOMP_P
  AH61  PCIE17_UP5_SATA5_RXN  BI  = SATA6G_PCH_PCIE_UP_SATA_RXN<5>
  AH65  PCIE16_UP4_SATA4_RXP  BI  = SATA6G_PCH_PCIE_UP_SATA_RXP<4>
  AH69  PCIE7_SSATA1_TXN  BI  = SATA6G_S1_TX_DN
  AH71  PCIE7_SSATA1_TXP  BI  = SATA6G_S1_TX_DP
  AJ1  GPP_K0_LAN_NCSI_CLK_IN  BI  = CLK_50M_CKMNG_PCH_10GBE
  AJ3  GPP_K8_LAN_NCSI_ARB_IN  BI  = RMII_PCH_SPRNGVLLE_ARB_IN
  AJ5  VSS(232)  GROUND  = GND
  AJ7  VSS(227)  GROUND  = GND
  AJ11  VSS(246)  GROUND  = GND
  AJ15  VSS(242)  GROUND  = GND
  AJ18  VSS(241)  GROUND  = GND
  AJ22  VSS(240)  GROUND  = GND
  AJ26  VSS(239)  GROUND  = GND
  AJ27  VCCPRTC  POWER  = P3V3_RTC_STBY
  AJ29  VCCPRIM_1P05(6)  POWER  = P1V05_PCH_STBY
  AJ30  VSS(238)  GROUND  = GND
  AJ32  VSS(245)  GROUND  = GND
  AJ34  VSS(237)  GROUND  = GND
  AJ36  VSS(236)  GROUND  = GND
  AJ37  VSS(235)  GROUND  = GND
  AJ39  VSS(234)  GROUND  = GND
  AJ41  VSS(233)  GROUND  = GND
  AJ43  VCCMPHY_1P05(2)  POWER  = P1V05_PCH_STBY
  AJ45  VSS(328)  GROUND  = GND
  AJ46  VCCA_CLKFILT_1P05(2)  POWER  = P1V05_PCH_STBY_ISCLK_PLL
  AJ48  VCCA_CLKFILT_1P05(3)  POWER  = P1V05_PCH_STBY_ISCLK_PLL
  AJ52  VSS(231)  GROUND  = GND
  AJ56  VSS(244)  GROUND  = GND
  AJ59  VSS(230)  GROUND  = GND
  AJ63  PCIE14_UP2_SATA2_RXP  BI  = SATA6G_PCH_PCIE_UP_SATA_RXP<2>
  AJ66  VSS(229)  GROUND  = GND
  AJ68  VSS(228)  GROUND  = GND
  AJ70  PCIE6_SSATA0_TXN  BI  = SATA6G_S0_TX_DN
  AJ72  PCIE6_SSATA0_TXP  BI  = SATA6G_S0_TX_DP
  AK2  GPP_K2_LAN_NCSI_TXD1  BI  = RMII_BMC_PCH_SPRNGVLLE_TXD1
  AK4  GPP_K9_LAN_NCSI_ARB_OUT  BI  = RMII_PCH_SPRNGVLLE_ARB_OUT_R
  AK9  GPP_F1_SATAXPCIE4_SATAGP4  BI  = FM_HSC_TIMER_EXP_N
  AK13  GPP_F3_SATAXPCIE6_SATAGP6  BI  = FM_MP_PS_REDUNDANT_LOST_N
  AK17  GPP_F7_SATA_DEVSLP5  BI  = JTAG_PCH_PLD_TDI
  AK20  GPP_F2_SATAXPCIE5_SATAGP5  BI  = FM_MP_PS_FAIL_N
  AK24  VCCPGPP_1P8(6)  POWER  = P1V8_PCH_STBY
  AK26  VSS(226)  GROUND  = GND
  AK27  VCCPRIM_1P05(17)  UNSPEC  = P1V05_PCH_STBY
  AK29  VCCPSPI_1P8  POWER  = P1V8_PCH_STBY
  AK30  VSS(243)  GROUND  = GND
  AK32  VCCPRIM_AVID(62)  UNSPEC  = PVNN_PCH_STBY
  AK34  VCCPRIM_AVID(18)  POWER  = PVNN_PCH_STBY
  AK36  VCCPRIM_AVID_SENSE  BI  = VSENSE_PVNN_PCH_STBY_FPK
  AK37  VCCPRIM_AVID(17)  POWER  = PVNN_PCH_STBY
  AK39  VCCPRIM_AVID(16)  POWER  = PVNN_PCH_STBY
  AK41  VSS(225)  GROUND  = GND
  AK43  VCCMPHY_1P05(12)  POWER  = P1V05_PCH_STBY
  AK45  VCCMPHY_1P05(11)  POWER  = P1V05_PCH_STBY
  AK46  VSS(224)  GROUND  = GND
  AK48  VSS(223)  GROUND  = GND
  AK50  VCCP_UPPLL_1P05(2)  POWER  = P1V05_PCH_STBY_WM20_PLL
  AK54  RSVD(36)  UNSPEC  = TP_PCH_RSVD36
  AK58  VSS(222)  GROUND  = GND
  AK61  VSS(221)  GROUND  = GND
  AK65  PCIE14_UP2_SATA2_RXN  BI  = SATA6G_PCH_PCIE_UP_SATA_RXN<2>
  AK69  VSS(220)  GROUND  = GND
  AK71  VSS(219)  GROUND  = GND
  AL1  GPP_K5_LAN_NCSI_RXD0  BI  = RMII_SPRNGVLLE_BMC_PCH_RXD0_R1
  AL3  GPP_K3_LAN_NCSI_TX_EN  BI  = RMII_BMC_PCH_SPRNGVLLE_TXEN
  AL5  VSS(217)  GROUND  = GND
  AL7  GPP_F10_SATA_SCLOCK  BI  = SGPIO_PCH_SATA_CLOCK
  AL11  GPP_F14_SSATA_LED_N  BI  = LED_PCH_SSATA_HDD_N
  AL15  GPP_F18_USB2_OC7_N  BI  = FM_MEM_THERM_EVENT_PCH_N
  AL18  GPP_F6_SATA_DEVSLP4  BI  = JTAG_PCH_PLD_TCK
  AL22  VSS(218)  GROUND  = GND
  AL52  VSS(216)  GROUND  = GND
  AL56  JTAG_TCK  BI  = XDP_PCH_TCK1
  AL59  VSS(215)  GROUND  = GND
  AL63  PCIE15_UP3_SATA3_RXP  BI  = SATA6G_PCH_PCIE_UP_SATA_RXP<3>
  AL66  PCIE13_UP1_SATA1_RXN  BI  = SATA6G_PCH_PCIE_UP_SATA_RXN<1>
  AL68  VSS(214)  GROUND  = GND
  AL70  VSS(213)  GROUND  = GND
  AL72  VSS(212)  GROUND  = GND
  AM2  GPP_K1_LAN_NCSI_TXD0  BI  = RMII_BMC_PCH_SPRNGVLLE_TXD0
  AM4  GPIO_RCOMP_1P8_3P3  BI  = A_1P8_3P3_RCOMP
  AM26  VSS(211)  GROUND  = GND
  AM27  VCCPRIM_1P05(5)  POWER  = P1V05_PCH_STBY
  AM29  VCCPGPP_1P8(3)  POWER  = P1V8_PCH_STBY
  AM30  VSS(210)  GROUND  = GND
  AM32  VCCPRIM_AVID(15)  POWER  = PVNN_PCH_STBY
  AM34  VCCPRIM_AVID(14)  POWER  = PVNN_PCH_STBY
  AM36  VCCPRIM_AVID(13)  POWER  = PVNN_PCH_STBY
  AM37  VCCPRIM_AVID(12)  POWER  = PVNN_PCH_STBY
  AM39  VCCPRIM_AVID(11)  POWER  = PVNN_PCH_STBY
  AM41  VSS(209)  GROUND  = GND
  AM43  VCCMPHY_1P05(10)  POWER  = P1V05_PCH_STBY
  AM45  VCCMPHY_1P05(9)  POWER  = P1V05_PCH_STBY
  AM46  VSS(208)  GROUND  = GND
  AM48  VCCP_UPPLLUNF_1P05  POWER  = P1V05_PCH_STBY
  AM69  PCIE5_GBE_RXN  BI  = PE_PCH_SPRV_RX_C_DN
  AM71  PCIE5_GBE_RXP  BI  = PE_PCH_SPRV_RX_C_DP
  AN1  GPP_K6_LAN_NCSI_RXD1  BI  = RMII_SPRNGVLLE_BMC_PCH_RXD1_R1
  AN3  GPP_K4_LAN_NCSI_CRS_DV  BI  = RMII_BMC_PCH_SPRNGVLLE_CRSDV_R1
  AN5  VSS(202)  GROUND  = GND
  AN9  VSS(200)  GROUND  = GND
  AN13  VSS(207)  GROUND  = GND
  AN17  VSS(206)  GROUND  = GND
  AN20  VSS(203)  GROUND  = GND
  AN24  VCCP_3P3(5)  UNSPEC  = P3V3_STBY
  AN50  VCCP_UPPLL_1P05(0)  POWER  = P1V05_PCH_STBY_WM20_PLL
  AN54  JTAG_TDI  BI  = XDP_TDI
  AN58  VSS(201)  GROUND  = GND
  AN61  PCIE18_UP6_SATA6_RXP  BI  = SATA6G_PCH_PCIE_UP_SATA_RXP<6>
  AN65  PCIE13_UP1_SATA1_RXP  BI  = SATA6G_PCH_PCIE_UP_SATA_RXP<1>
  AN68  VSS(205)  GROUND  = GND
  AN70  PCIE4_GBE_RXN  BI  = P2E_SSB_BMC_RX_C_DN
  AN72  PCIE4_GBE_RXP  BI  = P2E_SSB_BMC_RX_C_DP
  AP2  VSS(199)  GROUND  = GND
  AP4  VSS(196)  GROUND  = GND
  AP7  GPP_F12_SATA_SDATAOUT1  BI  = IRQ_SML1_PMBUS_ALERT_R1_N
  AP11  GPP_F13_SATA_SDATAOUT0  BI  = SGPIO_PCH_SATA_DOUT0
  AP15  GPP_F17_USB2_OC6_N  BI  = FM_BIOS_TOP_SWAP
  AP18  GPP_F22_SSATA_SCLOCK  BI  = SGPIO_PCH_SSATA_CLOCK
  AP22  VSS(204)  GROUND  = GND
  AP26  VSS(198)  GROUND  = GND
  AP27  RSVD(58)  UNSPEC  = TP_PCH_RSVD58
  AP29  VCCPGPP_1P8(4)  POWER  = P1V8_PCH_STBY
  AP30  VSS(197)  GROUND  = GND
  AP32  VCCPRIM_AVID(10)  POWER  = PVNN_PCH_STBY
